# S9S_MB_2U (Grand Teton) — schematic netlist excerpt (pin names and nets, part order shuffled) for the footprints in the layout excerpt that follows; sources: Cadence DE-HDL packaged netlist, KiCad conversion of 03242023_DA0F0TMBIJ0_F0T_Motherboard_J_brd_V01_OCP.brd

PC1243_P1_2  Q_CAP  2.2UF 10V 10% X6S  pkg C0402  page 289 : A = PVCCFA_EHV_FIVRA_CPU1_PVCC2 ; B = GND
R4044  Q_RES  33.2 1% CHIP  pkg 0402LF  page 225 : A = RST_CPU0_DRAM_EF_PLD_LVT3_R_N ; B = RST_CPU0_DRAM_EF_PLD_LVT3_N

(kicad_pcb
	(version 20260206)
	(generator "pcbnew")
	(generator_version "10.0")
	(general
		(thickness 1.6)
		(legacy_teardrops no)
	)
	(paper "A4")
	(title_block
		(title "03242023_DA0F0TMBIJ0_F0T_Motherboard_J_brd_V01_OCP.brd")
		(comment 1 "Grand Teton / footprints 1195-1196 of 6105")
	)
	(layers
		(0 "F.Cu" signal "TOP")
		(4 "In1.Cu" signal "GND")
		(6 "In2.Cu" signal "IN1")
		(8 "In3.Cu" signal "GND1")
		(10 "In4.Cu" signal "IN2")
		(12 "In5.Cu" signal "GND2")
		(14 "In6.Cu" signal "IN3")
		(16 "In7.Cu" signal "GND3")
		(18 "In8.Cu" signal "VCC")
		(20 "In9.Cu" signal "VCC1")
		(22 "In10.Cu" signal "GND4")
		(24 "In11.Cu" signal "IN4")
		(26 "In12.Cu" signal "GND5")
		(28 "In13.Cu" signal "IN5")
		(30 "In14.Cu" signal "GND6")
		(32 "In15.Cu" signal "IN6")
		(34 "In16.Cu" signal "GND7")
		(2 "B.Cu" signal "BOTTOM")
		(9 "F.Adhes" user "F.Adhesive")
		(11 "B.Adhes" user "B.Adhesive")
		(13 "F.Paste" user "Package Geometry/Pastemask Top")
		(15 "B.Paste" user "Package Geometry/Pastemask Bottom")
		(5 "F.SilkS" user "Ref Des/Silkscreen Top")
		(7 "B.SilkS" user "Ref Des/Silkscreen Bottom")
		(1 "F.Mask" user "Board Geometry/Soldermask Top")
		(3 "B.Mask" user "Board Geometry/Soldermask Bottom")
		(17 "Dwgs.User" user "User.Drawings")
		(19 "Cmts.User" user "User.Comments")
		(21 "Eco1.User" user "User.Eco1")
		(23 "Eco2.User" user "User.Eco2")
		(25 "Edge.Cuts" user "Board Geometry/Outline")
		(27 "Margin" user)
		(31 "F.CrtYd" user "Package Geometry/Place Bound Top")
		(29 "B.CrtYd" user "Package Geometry/Place Bound Bottom")
		(35 "F.Fab" user "Ref Des/Assembly Top")
		(33 "B.Fab" user "Ref Des/Assembly Bottom")
	)
	(footprint ""
		(layer "F.Cu")
		(at 47.678594 -353.35718 -90)
		(property "Reference" "PC1243_P1_2"
			(at 0 0 270)
			(layer "F.SilkS")
			(hide yes)
			(effects
				(font
					(size 1.27 1.27)
				)
			)
		)
		(property "Value" ""
			(at 0 0 270)
			(layer "F.Fab")
			(effects
				(font
					(size 1.27 1.27)
				)
			)
		)
		(duplicate_pad_numbers_are_jumpers no)
		(fp_line
			(start -0.7874 0.4064)
			(end -0.7874 -0.4064)
			(stroke
				(width 0.1524)
				(type default)
			)
			(layer "F.SilkS")
		)
		(fp_line
			(start 0.7874 0.4064)
			(end -0.7874 0.4064)
			(stroke
				(width 0.1524)
				(type default)
			)
			(layer "F.SilkS")
		)
		(fp_line
			(start -0.7874 -0.4064)
			(end 0.7874 -0.4064)
			(stroke
				(width 0.1524)
				(type default)
			)
			(layer "F.SilkS")
		)
		(fp_line
			(start 0.7874 -0.4064)
			(end 0.7874 0.4064)
			(stroke
				(width 0.1524)
				(type default)
			)
			(layer "F.SilkS")
		)
		(fp_line
			(start -0.67945 0.3048)
			(end -0.67945 -0.305054)
			(stroke
				(width 0.1)
				(type default)
			)
			(layer "F.Fab")
		)
		(fp_line
			(start -0.12065 0.3048)
			(end -0.67945 0.3048)
			(stroke
				(width 0.1)
				(type default)
			)
			(layer "F.Fab")
		)
		(fp_line
			(start 0.120396 0.3048)
			(end 0.120396 0.2794)
			(stroke
				(width 0.1)
				(type default)
			)
			(layer "F.Fab")
		)
		(fp_line
			(start 0.67945 0.3048)
			(end 0.120396 0.3048)
			(stroke
				(width 0.1)
				(type default)
			)
			(layer "F.Fab")
		)
		(fp_line
			(start -0.12065 0.2794)
			(end -0.12065 0.3048)
			(stroke
				(width 0.1)
				(type default)
			)
			(layer "F.Fab")
		)
		(fp_line
			(start 0.120396 0.2794)
			(end -0.12065 0.2794)
			(stroke
				(width 0.1)
				(type default)
			)
			(layer "F.Fab")
		)
		(fp_line
			(start -0.12065 -0.2794)
			(end 0.12065 -0.2794)
			(stroke
				(width 0.1)
				(type default)
			)
			(layer "F.Fab")
		)
		(fp_line
			(start 0.12065 -0.2794)
			(end 0.12065 -0.3048)
			(stroke
				(width 0.1)
				(type default)
			)
			(layer "F.Fab")
		)
		(fp_line
			(start 0.12065 -0.3048)
			(end 0.67945 -0.3048)
			(stroke
				(width 0.1)
				(type default)
			)
			(layer "F.Fab")
		)
		(fp_line
			(start 0.67945 -0.3048)
			(end 0.67945 0.3048)
			(stroke
				(width 0.1)
				(type default)
			)
			(layer "F.Fab")
		)
		(fp_line
			(start -0.67945 -0.305054)
			(end -0.12065 -0.305054)
			(stroke
				(width 0.1)
				(type default)
			)
			(layer "F.Fab")
		)
		(fp_line
			(start -0.12065 -0.305054)
			(end -0.12065 -0.2794)
			(stroke
				(width 0.1)
				(type default)
			)
			(layer "F.Fab")
		)
		(pad "1" smd circle
			(at -0.40005 0 270)
			(size 0 0)
			(layers "F.Cu" "F.Mask" "F.Paste")
			(net "PVCCFA_EHV_FIVRA_CPU1_PVCC2")
		)
		(pad "2" smd circle
			(at 0.40005 0 270)
			(size 0 0)
			(layers "F.Cu" "F.Mask" "F.Paste")
			(net "GND")
		)
	)
	(footprint ""
		(layer "F.Cu")
		(at 115.06708 -106.238548 -90)
		(property "Reference" "R4044"
			(at 0 0 270)
			(layer "F.SilkS")
			(hide yes)
			(effects
				(font
					(size 1.27 1.27)
				)
			)
		)
		(property "Value" ""
			(at 0 0 270)
			(layer "F.Fab")
			(effects
				(font
					(size 1.27 1.27)
				)
			)
		)
		(duplicate_pad_numbers_are_jumpers no)
		(fp_line
			(start -0.7874 0.4064)
			(end -0.7874 -0.4064)
			(stroke
				(width 0.1524)
				(type default)
			)
			(layer "F.SilkS")
		)
		(fp_line
			(start 0.7874 0.4064)
			(end -0.7874 0.4064)
			(stroke
				(width 0.1524)
				(type default)
			)
			(layer "F.SilkS")
		)
		(fp_line
			(start -0.7874 -0.4064)
			(end 0.7874 -0.4064)
			(stroke
				(width 0.1524)
				(type default)
			)
			(layer "F.SilkS")
		)
		(fp_line
			(start 0.7874 -0.4064)
			(end 0.7874 0.4064)
			(stroke
				(width 0.1524)
				(type default)
			)
			(layer "F.SilkS")
		)
		(fp_line
			(start -0.67945 0.3048)
			(end -0.67945 -0.305054)
			(stroke
				(width 0.1)
				(type default)
			)
			(layer "F.Fab")
		)
		(fp_line
			(start -0.12065 0.3048)
			(end -0.67945 0.3048)
			(stroke
				(width 0.1)
				(type default)
			)
			(layer "F.Fab")
		)
		(fp_line
			(start 0.120396 0.3048)
			(end 0.120396 0.2794)
			(stroke
				(width 0.1)
				(type default)
			)
			(layer "F.Fab")
		)
		(fp_line
			(start 0.67945 0.3048)
			(end 0.120396 0.3048)
			(stroke
				(width 0.1)
				(type default)
			)
			(layer "F.Fab")
		)
		(fp_line
			(start -0.12065 0.2794)
			(end -0.12065 0.3048)
			(stroke
				(width 0.1)
				(type default)
			)
			(layer "F.Fab")
		)
		(fp_line
			(start 0.120396 0.2794)
			(end -0.12065 0.2794)
			(stroke
				(width 0.1)
				(type default)
			)
			(layer "F.Fab")
		)
		(fp_line
			(start -0.12065 -0.2794)
			(end 0.12065 -0.2794)
			(stroke
				(width 0.1)
				(type default)
			)
			(layer "F.Fab")
		)
		(fp_line
			(start 0.12065 -0.2794)
			(end 0.12065 -0.3048)
			(stroke
				(width 0.1)
				(type default)
			)
			(layer "F.Fab")
		)
		(fp_line
			(start 0.12065 -0.3048)
			(end 0.67945 -0.3048)
			(stroke
				(width 0.1)
				(type default)
			)
			(layer "F.Fab")
		)
		(fp_line
			(start 0.67945 -0.3048)
			(end 0.67945 0.3048)
			(stroke
				(width 0.1)
				(type default)
			)
			(layer "F.Fab")
		)
		(fp_line
			(start -0.67945 -0.305054)
			(end -0.12065 -0.305054)
			(stroke
				(width 0.1)
				(type default)
			)
			(layer "F.Fab")
		)
		(fp_line
			(start -0.12065 -0.305054)
			(end -0.12065 -0.2794)
			(stroke
				(width 0.1)
				(type default)
			)
			(layer "F.Fab")
		)
		(pad "1" smd circle
			(at -0.40005 0 270)
			(size 0 0)
			(layers "F.Cu" "F.Mask" "F.Paste")
			(net "RST_CPU0_DRAM_EF_PLD_LVT3_R_N")
		)
		(pad "2" smd circle
			(at 0.40005 0 270)
			(size 0 0)
			(layers "F.Cu" "F.Mask" "F.Paste")
			(net "RST_CPU0_DRAM_EF_PLD_LVT3_N")
		)
	)
)
